# T6G (Grand Teton) — schematic netlist excerpt (pin names and nets, part order shuffled) for the footprints in the layout excerpt that follows; sources: Cadence DE-HDL packaged netlist, KiCad conversion of 04192023_DAF0TMB3IC0_F0TG_MB_C_brd_V02_OCP.brd

PR3791  Q_RES  15K 1% CHIP  pkg 0402LF  page 134 : A = P3V3_OCP_OV_1 ; B = GND
PC2197  Q_CAP  39PF 50V 5% NPO  pkg 0402  page 147 : A = P3V3_E1S_MODE_0 ; B = GND
R1013  Q_RES  1K 1% CHIP  pkg 0201LF  page 287 : A = P1V8_CPU0_RT_1D ; B = RT_CPU0_P1_ADDR3

(kicad_pcb
	(version 20260206)
	(generator "pcbnew")
	(generator_version "10.0")
	(general
		(thickness 1.6)
		(legacy_teardrops no)
	)
	(paper "A4")
	(title_block
		(title "04192023_DAF0TMB3IC0_F0TG_MB_C_brd_V02_OCP.brd")
		(comment 1 "Grand Teton / footprints 997-999 of 8354")
	)
	(layers
		(0 "F.Cu" signal "TOP")
		(4 "In1.Cu" signal "GND")
		(6 "In2.Cu" signal "IN1")
		(8 "In3.Cu" signal "GND1")
		(10 "In4.Cu" signal "IN2")
		(12 "In5.Cu" signal "GND2")
		(14 "In6.Cu" signal "IN3")
		(16 "In7.Cu" signal "GND3")
		(18 "In8.Cu" signal "VCC")
		(20 "In9.Cu" signal "VCC1")
		(22 "In10.Cu" signal "GND4")
		(24 "In11.Cu" signal "IN4")
		(26 "In12.Cu" signal "GND5")
		(28 "In13.Cu" signal "IN5")
		(30 "In14.Cu" signal "GND6")
		(32 "In15.Cu" signal "IN6")
		(34 "In16.Cu" signal "GND7")
		(2 "B.Cu" signal "BOTTOM")
		(9 "F.Adhes" user "F.Adhesive")
		(11 "B.Adhes" user "B.Adhesive")
		(13 "F.Paste" user "Package Geometry/Pastemask Top")
		(15 "B.Paste" user "Package Geometry/Pastemask Bottom")
		(5 "F.SilkS" user "Ref Des/Silkscreen Top")
		(7 "B.SilkS" user "Ref Des/Silkscreen Bottom")
		(1 "F.Mask" user "Board Geometry/Soldermask Top")
		(3 "B.Mask" user "Board Geometry/Soldermask Bottom")
		(17 "Dwgs.User" user "User.Drawings")
		(19 "Cmts.User" user "User.Comments")
		(21 "Eco1.User" user "User.Eco1")
		(23 "Eco2.User" user "User.Eco2")
		(25 "Edge.Cuts" user "Board Geometry/Outline")
		(27 "Margin" user)
		(31 "F.CrtYd" user "Package Geometry/Place Bound Top")
		(29 "B.CrtYd" user "Package Geometry/Place Bound Bottom")
		(35 "F.Fab" user "Ref Des/Assembly Top")
		(33 "B.Fab" user "Ref Des/Assembly Bottom")
	)
	(footprint ""
		(layer "F.Cu")
		(at 428.283116 -109.26699 90)
		(property "Reference" "PR3791"
			(at 0 0 90)
			(layer "F.SilkS")
			(hide yes)
			(effects
				(font
					(size 1.27 1.27)
				)
			)
		)
		(property "Value" ""
			(at 0 0 90)
			(layer "F.Fab")
			(effects
				(font
					(size 1.27 1.27)
				)
			)
		)
		(duplicate_pad_numbers_are_jumpers no)
		(fp_line
			(start 0.7874 -0.4064)
			(end 0.7874 0.4064)
			(stroke
				(width 0.1524)
				(type default)
			)
			(layer "F.SilkS")
		)
		(fp_line
			(start -0.7874 -0.4064)
			(end 0.7874 -0.4064)
			(stroke
				(width 0.1524)
				(type default)
			)
			(layer "F.SilkS")
		)
		(fp_line
			(start 0.7874 0.4064)
			(end -0.7874 0.4064)
			(stroke
				(width 0.1524)
				(type default)
			)
			(layer "F.SilkS")
		)
		(fp_line
			(start -0.7874 0.4064)
			(end -0.7874 -0.4064)
			(stroke
				(width 0.1524)
				(type default)
			)
			(layer "F.SilkS")
		)
		(fp_line
			(start -0.12065 -0.305054)
			(end -0.12065 -0.2794)
			(stroke
				(width 0.1)
				(type default)
			)
			(layer "F.Fab")
		)
		(fp_line
			(start -0.67945 -0.305054)
			(end -0.12065 -0.305054)
			(stroke
				(width 0.1)
				(type default)
			)
			(layer "F.Fab")
		)
		(fp_line
			(start 0.67945 -0.3048)
			(end 0.67945 0.3048)
			(stroke
				(width 0.1)
				(type default)
			)
			(layer "F.Fab")
		)
		(fp_line
			(start 0.12065 -0.3048)
			(end 0.67945 -0.3048)
			(stroke
				(width 0.1)
				(type default)
			)
			(layer "F.Fab")
		)
		(fp_line
			(start 0.12065 -0.2794)
			(end 0.12065 -0.3048)
			(stroke
				(width 0.1)
				(type default)
			)
			(layer "F.Fab")
		)
		(fp_line
			(start -0.12065 -0.2794)
			(end 0.12065 -0.2794)
			(stroke
				(width 0.1)
				(type default)
			)
			(layer "F.Fab")
		)
		(fp_line
			(start 0.120396 0.2794)
			(end -0.12065 0.2794)
			(stroke
				(width 0.1)
				(type default)
			)
			(layer "F.Fab")
		)
		(fp_line
			(start -0.12065 0.2794)
			(end -0.12065 0.3048)
			(stroke
				(width 0.1)
				(type default)
			)
			(layer "F.Fab")
		)
		(fp_line
			(start 0.67945 0.3048)
			(end 0.120396 0.3048)
			(stroke
				(width 0.1)
				(type default)
			)
			(layer "F.Fab")
		)
		(fp_line
			(start 0.120396 0.3048)
			(end 0.120396 0.2794)
			(stroke
				(width 0.1)
				(type default)
			)
			(layer "F.Fab")
		)
		(fp_line
			(start -0.12065 0.3048)
			(end -0.67945 0.3048)
			(stroke
				(width 0.1)
				(type default)
			)
			(layer "F.Fab")
		)
		(fp_line
			(start -0.67945 0.3048)
			(end -0.67945 -0.305054)
			(stroke
				(width 0.1)
				(type default)
			)
			(layer "F.Fab")
		)
		(pad "1" smd circle
			(at -0.40005 0 90)
			(size 0 0)
			(layers "F.Cu" "F.Mask" "F.Paste")
			(net "P3V3_OCP_OV_1")
		)
		(pad "2" smd circle
			(at 0.40005 0 90)
			(size 0 0)
			(layers "F.Cu" "F.Mask" "F.Paste")
			(net "GND")
		)
	)
	(footprint ""
		(layer "F.Cu")
		(at 360.40949 -393.9032 90)
		(property "Reference" "R1013"
			(at 0 0 90)
			(layer "F.SilkS")
			(hide yes)
			(effects
				(font
					(size 1.27 1.27)
				)
			)
		)
		(property "Value" ""
			(at 0 0 90)
			(layer "F.Fab")
			(effects
				(font
					(size 1.27 1.27)
				)
			)
		)
		(duplicate_pad_numbers_are_jumpers no)
		(fp_line
			(start 0.32512 -0.175006)
			(end 0.32512 0.175006)
			(stroke
				(width 0.1)
				(type default)
			)
			(layer "F.Fab")
		)
		(fp_line
			(start -0.32512 -0.175006)
			(end 0.32512 -0.175006)
			(stroke
				(width 0.1)
				(type default)
			)
			(layer "F.Fab")
		)
		(fp_line
			(start 0.32512 0.175006)
			(end -0.32512 0.175006)
			(stroke
				(width 0.1)
				(type default)
			)
			(layer "F.Fab")
		)
		(fp_line
			(start -0.32512 0.175006)
			(end -0.32512 -0.175006)
			(stroke
				(width 0.1)
				(type default)
			)
			(layer "F.Fab")
		)
		(pad "1" smd rect
			(at -0.2667 0 90)
			(size 0.3048 0.381)
			(layers "F.Cu" "F.Mask" "F.Paste")
			(net "P1V8_CPU0_RT_1D")
		)
		(pad "2" smd rect
			(at 0.2667 0 270)
			(size 0.3048 0.381)
			(layers "F.Cu" "F.Mask" "F.Paste")
			(net "RT_CPU0_P1_ADDR3")
		)
	)
	(footprint ""
		(layer "F.Cu")
		(at 192.599564 -68.407788 180)
		(property "Reference" "PC2197"
			(at 0 0 180)
			(layer "F.SilkS")
			(hide yes)
			(effects
				(font
					(size 1.27 1.27)
				)
			)
		)
		(property "Value" ""
			(at 0 0 180)
			(layer "F.Fab")
			(effects
				(font
					(size 1.27 1.27)
				)
			)
		)
		(duplicate_pad_numbers_are_jumpers no)
		(fp_line
			(start 0.7874 0.4064)
			(end -0.7874 0.4064)
			(stroke
				(width 0.1524)
				(type default)
			)
			(layer "F.SilkS")
		)
		(fp_line
			(start 0.7874 -0.4064)
			(end 0.7874 0.4064)
			(stroke
				(width 0.1524)
				(type default)
			)
			(layer "F.SilkS")
		)
		(fp_line
			(start -0.7874 0.4064)
			(end -0.7874 -0.4064)
			(stroke
				(width 0.1524)
				(type default)
			)
			(layer "F.SilkS")
		)
		(fp_line
			(start -0.7874 -0.4064)
			(end 0.7874 -0.4064)
			(stroke
				(width 0.1524)
				(type default)
			)
			(layer "F.SilkS")
		)
		(fp_line
			(start 0.67945 0.3048)
			(end 0.120396 0.3048)
			(stroke
				(width 0.1)
				(type default)
			)
			(layer "F.Fab")
		)
		(fp_line
			(start 0.67945 -0.3048)
			(end 0.67945 0.3048)
			(stroke
				(width 0.1)
				(type default)
			)
			(layer "F.Fab")
		)
		(fp_line
			(start 0.12065 -0.2794)
			(end 0.12065 -0.3048)
			(stroke
				(width 0.1)
				(type default)
			)
			(layer "F.Fab")
		)
		(fp_line
			(start 0.12065 -0.3048)
			(end 0.67945 -0.3048)
			(stroke
				(width 0.1)
				(type default)
			)
			(layer "F.Fab")
		)
		(fp_line
			(start 0.120396 0.3048)
			(end 0.120396 0.2794)
			(stroke
				(width 0.1)
				(type default)
			)
			(layer "F.Fab")
		)
		(fp_line
			(start 0.120396 0.2794)
			(end -0.12065 0.2794)
			(stroke
				(width 0.1)
				(type default)
			)
			(layer "F.Fab")
		)
		(fp_line
			(start -0.12065 0.3048)
			(end -0.67945 0.3048)
			(stroke
				(width 0.1)
				(type default)
			)
			(layer "F.Fab")
		)
		(fp_line
			(start -0.12065 0.2794)
			(end -0.12065 0.3048)
			(stroke
				(width 0.1)
				(type default)
			)
			(layer "F.Fab")
		)
		(fp_line
			(start -0.12065 -0.2794)
			(end 0.12065 -0.2794)
			(stroke
				(width 0.1)
				(type default)
			)
			(layer "F.Fab")
		)
		(fp_line
			(start -0.12065 -0.305054)
			(end -0.12065 -0.2794)
			(stroke
				(width 0.1)
				(type default)
			)
			(layer "F.Fab")
		)
		(fp_line
			(start -0.67945 0.3048)
			(end -0.67945 -0.305054)
			(stroke
				(width 0.1)
				(type default)
			)
			(layer "F.Fab")
		)
		(fp_line
			(start -0.67945 -0.305054)
			(end -0.12065 -0.305054)
			(stroke
				(width 0.1)
				(type default)
			)
			(layer "F.Fab")
		)
		(pad "1" smd circle
			(at -0.40005 0 180)
			(size 0 0)
			(layers "F.Cu" "F.Mask" "F.Paste")
			(net "P3V3_E1S_MODE_0")
		)
		(pad "2" smd circle
			(at 0.40005 0 180)
			(size 0 0)
			(layers "F.Cu" "F.Mask" "F.Paste")
			(net "GND")
		)
	)
)
